# BASEBOARD_FAB2 (Tioga Pass) — schematic netlist excerpt (pin names and nets, part order shuffled) for the footprints in the layout excerpt that follows; sources: Cadence DE-HDL packaged netlist, KiCad conversion of Wiwynn_Tioga_Pass_MB.brd

R1W11  RES  0.0 5% EMPTY  pkg 0805  page 176 : A = P5V ; B = P5V_TPS2061
C5G110  CAP_A  22.0UF 4V 20% X6S  pkg 0603V  page 243 : A = PVDDQ_KLM ; B = GND
C5T7  CAP_A  47UF 4V 20% X5R  pkg 0603V  page 217 : A = PVDDQ_ABC ; B = GND

(kicad_pcb
	(version 20260206)
	(generator "pcbnew")
	(generator_version "10.0")
	(general
		(thickness 1.6)
		(legacy_teardrops no)
	)
	(paper "A4")
	(title_block
		(title "Wiwynn_Tioga_Pass_MB.brd")
		(comment 1 "Tioga Pass / footprints 3907-3909 of 4770")
	)
	(layers
		(0 "F.Cu" signal "TOP")
		(4 "In1.Cu" signal "L2GND")
		(6 "In2.Cu" signal "L3")
		(8 "In3.Cu" signal "L4GND")
		(10 "In4.Cu" signal "L5")
		(12 "In5.Cu" signal "L6GND")
		(14 "In6.Cu" signal "L7VCC")
		(16 "In7.Cu" signal "L8VCC")
		(18 "In8.Cu" signal "L9GND")
		(20 "In9.Cu" signal "L10")
		(22 "In10.Cu" signal "L11GND")
		(24 "In11.Cu" signal "L12")
		(26 "In12.Cu" signal "L13GND")
		(2 "B.Cu" signal "BOTTOM")
		(9 "F.Adhes" user "F.Adhesive")
		(11 "B.Adhes" user "B.Adhesive")
		(13 "F.Paste" user "Package Geometry/Pastemask Top")
		(15 "B.Paste" user "Package Geometry/Pastemask Bottom")
		(5 "F.SilkS" user "Ref Des/Silkscreen Top")
		(7 "B.SilkS" user "Ref Des/Silkscreen Bottom")
		(1 "F.Mask" user "Board Geometry/Soldermask Top")
		(3 "B.Mask" user "Board Geometry/Soldermask Bottom")
		(17 "Dwgs.User" user "User.Drawings")
		(19 "Cmts.User" user "User.Comments")
		(21 "Eco1.User" user "User.Eco1")
		(23 "Eco2.User" user "User.Eco2")
		(25 "Edge.Cuts" user "Board Geometry/Outline")
		(27 "Margin" user)
		(31 "F.CrtYd" user "Package Geometry/Place Bound Top")
		(29 "B.CrtYd" user "Package Geometry/Place Bound Bottom")
		(35 "F.Fab" user "Ref Des/Assembly Top")
		(33 "B.Fab" user "Ref Des/Assembly Bottom")
	)
	(footprint ""
		(layer "B.Cu")
		(at 269.559532 -17.7546 90)
		(property "Reference" "C5T7"
			(at -1.848866 0.752348 90)
			(unlocked yes)
			(layer "B.SilkS")
			(effects
				(font
					(size 1.27 0.9652)
					(thickness 0.1524)
				)
				(justify mirror)
			)
		)
		(property "Value" ""
			(at 0 0 90)
			(layer "B.Fab")
			(effects
				(font
					(size 1.27 1.27)
				)
				(justify mirror)
			)
		)
		(duplicate_pad_numbers_are_jumpers no)
		(fp_rect
			(start 0.500126 1.598422)
			(end -0.500126 -0.201422)
			(stroke
				(width 0)
				(type default)
			)
			(fill no)
			(layer "B.CrtYd")
		)
		(fp_line
			(start 0.500126 -0.201422)
			(end -0.500126 -0.201422)
			(stroke
				(width 0.1)
				(type default)
			)
			(layer "B.Fab")
		)
		(fp_line
			(start -0.500126 -0.201422)
			(end -0.500126 1.598422)
			(stroke
				(width 0.1)
				(type default)
			)
			(layer "B.Fab")
		)
		(fp_line
			(start 0.500126 1.598422)
			(end 0.500126 -0.201422)
			(stroke
				(width 0.1)
				(type default)
			)
			(layer "B.Fab")
		)
		(fp_line
			(start -0.500126 1.598422)
			(end 0.500126 1.598422)
			(stroke
				(width 0.1)
				(type default)
			)
			(layer "B.Fab")
		)
		(pad "1" smd rect
			(at 0 0)
			(size 0.889 0.9906)
			(layers "B.Cu" "B.Mask" "B.Paste")
			(net "PVDDQ_ABC")
		)
		(pad "2" smd rect
			(at 0 1.397)
			(size 0.889 0.9906)
			(layers "B.Cu" "B.Mask" "B.Paste")
			(net "GND")
		)
		(zone
			(layer "B.Cu")
			(hatch none 0.5)
			(connect_pads
				(clearance 0)
			)
			(min_thickness 0.25)
			(keepout
				(tracks not_allowed)
				(vias allowed)
				(pads allowed)
				(copperpour not_allowed)
				(footprints allowed)
			)
			(placement
				(enabled no)
				(sheetname "")
			)
			(fill
				(thermal_gap 0.5)
				(thermal_bridge_width 0.5)
				(island_removal_mode 0)
			)
			(polygon
				(pts
					(xy 270.512032 -18.2499) (xy 270.004032 -18.2499) (xy 270.004032 -17.2593) (xy 270.512032 -17.2593)
				)
			)
		)
		(zone
			(layer "B.Cu")
			(hatch none 0.5)
			(connect_pads
				(clearance 0)
			)
			(min_thickness 0.25)
			(keepout
				(tracks allowed)
				(vias not_allowed)
				(pads allowed)
				(copperpour not_allowed)
				(footprints allowed)
			)
			(placement
				(enabled no)
				(sheetname "")
			)
			(fill
				(thermal_gap 0.5)
				(thermal_bridge_width 0.5)
				(island_removal_mode 0)
			)
			(polygon
				(pts
					(xy 270.512032 -18.2499) (xy 270.004032 -18.2499) (xy 270.004032 -17.2593) (xy 270.512032 -17.2593)
				)
			)
		)
	)
	(footprint ""
		(layer "B.Cu")
		(at 466.5472 -125.095 -90)
		(property "Reference" "R1W11"
			(at -1.47828 0.78994 0)
			(unlocked yes)
			(layer "B.SilkS")
			(effects
				(font
					(size 0.4064 0.254)
					(thickness 0.1524)
				)
				(justify mirror)
			)
		)
		(property "Value" ""
			(at 0 0 90)
			(layer "B.Fab")
			(effects
				(font
					(size 1.27 1.27)
				)
				(justify mirror)
			)
		)
		(duplicate_pad_numbers_are_jumpers no)
		(fp_poly
			(pts
				(xy 0.7239 -0.2159) (xy -0.7239 -0.2159) (xy -0.7239 1.9939) (xy 0.7239 1.9939)
			)
			(stroke
				(width 0)
				(type default)
			)
			(fill no)
			(layer "B.CrtYd")
		)
		(fp_line
			(start -0.7239 1.9939)
			(end -0.7239 -0.2159)
			(stroke
				(width 0.1)
				(type default)
			)
			(layer "B.Fab")
		)
		(fp_line
			(start 0.7239 1.9939)
			(end -0.7239 1.9939)
			(stroke
				(width 0.1)
				(type default)
			)
			(layer "B.Fab")
		)
		(fp_line
			(start -0.7239 -0.2159)
			(end 0.7239 -0.2159)
			(stroke
				(width 0.1)
				(type default)
			)
			(layer "B.Fab")
		)
		(fp_line
			(start 0.7239 -0.2159)
			(end 0.7239 1.9939)
			(stroke
				(width 0.1)
				(type default)
			)
			(layer "B.Fab")
		)
		(pad "1" smd rect
			(at 0 0 90)
			(size 1.27 1.016)
			(layers "B.Cu" "B.Mask" "B.Paste")
			(net "P5V")
		)
		(pad "2" smd rect
			(at 0 1.778 90)
			(size 1.27 1.016)
			(layers "B.Cu" "B.Mask" "B.Paste")
			(net "P5V_TPS2061")
		)
		(zone
			(layer "B.Cu")
			(hatch none 0.5)
			(connect_pads
				(clearance 0)
			)
			(min_thickness 0.25)
			(keepout
				(tracks not_allowed)
				(vias allowed)
				(pads allowed)
				(copperpour not_allowed)
				(footprints allowed)
			)
			(placement
				(enabled no)
				(sheetname "")
			)
			(fill
				(thermal_gap 0.5)
				(thermal_bridge_width 0.5)
				(island_removal_mode 0)
			)
			(polygon
				(pts
					(xy 466.0392 -125.73) (xy 465.2772 -125.73) (xy 465.2772 -125.6411) (xy 465.2772 -124.46) (xy 466.0392 -124.46)
				)
			)
		)
	)
	(footprint ""
		(layer "B.Cu")
		(at 93.05798 -140.16228 -90)
		(property "Reference" "C5G110"
			(at -1.14681 0.76708 0)
			(unlocked yes)
			(layer "B.SilkS")
			(effects
				(font
					(size 0.7874 0.5842)
					(thickness 0.1524)
				)
				(justify mirror)
			)
		)
		(property "Value" ""
			(at 0 0 90)
			(layer "B.Fab")
			(effects
				(font
					(size 1.27 1.27)
				)
				(justify mirror)
			)
		)
		(duplicate_pad_numbers_are_jumpers no)
		(fp_rect
			(start -0.4953 -0.2032)
			(end 0.4953 1.6002)
			(stroke
				(width 0)
				(type default)
			)
			(fill no)
			(layer "B.CrtYd")
		)
		(fp_line
			(start -0.4953 1.6002)
			(end 0.4953 1.6002)
			(stroke
				(width 0.1)
				(type default)
			)
			(layer "B.Fab")
		)
		(fp_line
			(start 0.4953 1.6002)
			(end 0.4953 -0.2032)
			(stroke
				(width 0.1)
				(type default)
			)
			(layer "B.Fab")
		)
		(fp_line
			(start -0.4953 -0.2032)
			(end -0.4953 1.6002)
			(stroke
				(width 0.1)
				(type default)
			)
			(layer "B.Fab")
		)
		(fp_line
			(start 0.4953 -0.2032)
			(end -0.4953 -0.2032)
			(stroke
				(width 0.1)
				(type default)
			)
			(layer "B.Fab")
		)
		(pad "1" smd rect
			(at 0 0 90)
			(size 0.762 0.889)
			(layers "B.Cu" "B.Mask" "B.Paste")
			(net "PVDDQ_KLM")
		)
		(pad "2" smd rect
			(at 0 1.397 90)
			(size 0.762 0.889)
			(layers "B.Cu" "B.Mask" "B.Paste")
			(net "GND")
		)
		(zone
			(layer "B.Cu")
			(hatch none 0.5)
			(connect_pads
				(clearance 0)
			)
			(min_thickness 0.25)
			(keepout
				(tracks not_allowed)
				(vias allowed)
				(pads allowed)
				(copperpour not_allowed)
				(footprints allowed)
			)
			(placement
				(enabled no)
				(sheetname "")
			)
			(fill
				(thermal_gap 0.5)
				(thermal_bridge_width 0.5)
				(island_removal_mode 0)
			)
			(polygon
				(pts
					(xy 92.61348 -140.54328) (xy 92.10548 -140.54328) (xy 92.10548 -139.78128) (xy 92.61348 -139.78128)
				)
			)
		)
	)
)
